# SCM (Grand Teton) — schematic netlist excerpt (pin names and nets, part order shuffled) for the footprints in the layout excerpt that follows; sources: Cadence DE-HDL packaged netlist, KiCad conversion of 12092022_DA0F0TMDCD0_F0T_Management_Board_D_brd_V3_OCP.brd

R556  Q_RES  33.2 1% CHIP  pkg 0402LF  page 25 : A = SPI_BMC_BT_WP1_N_R ; B = FLASH_LATCH_Q_N_R2
C312  Q_CAP  0.1UF 25V 10% X7R  pkg 0402  page 25 : A = P3V3_AUX ; B = GND

(kicad_pcb
	(version 20260206)
	(generator "pcbnew")
	(generator_version "10.0")
	(general
		(thickness 1.6)
		(legacy_teardrops no)
	)
	(paper "A4")
	(title_block
		(title "12092022_DA0F0TMDCD0_F0T_Management_Board_D_brd_V3_OCP.brd")
		(comment 1 "Grand Teton / footprints 19-20 of 1440")
	)
	(layers
		(0 "F.Cu" signal "TOP")
		(4 "In1.Cu" signal "GND")
		(6 "In2.Cu" signal "IN1")
		(8 "In3.Cu" signal "GND1")
		(10 "In4.Cu" signal "IN2")
		(12 "In5.Cu" signal "VCC")
		(14 "In6.Cu" signal "VCC1")
		(16 "In7.Cu" signal "IN3")
		(18 "In8.Cu" signal "GND2")
		(20 "In9.Cu" signal "IN4")
		(22 "In10.Cu" signal "GND3")
		(2 "B.Cu" signal "BOTTOM")
		(9 "F.Adhes" user "F.Adhesive")
		(11 "B.Adhes" user "B.Adhesive")
		(13 "F.Paste" user "Package Geometry/Pastemask Top")
		(15 "B.Paste" user "Package Geometry/Pastemask Bottom")
		(5 "F.SilkS" user "Ref Des/Silkscreen Top")
		(7 "B.SilkS" user "Ref Des/Silkscreen Bottom")
		(1 "F.Mask" user "Board Geometry/Soldermask Top")
		(3 "B.Mask" user "Board Geometry/Soldermask Bottom")
		(17 "Dwgs.User" user "User.Drawings")
		(19 "Cmts.User" user "User.Comments")
		(21 "Eco1.User" user "User.Eco1")
		(23 "Eco2.User" user "User.Eco2")
		(25 "Edge.Cuts" user "Board Geometry/Outline")
		(27 "Margin" user)
		(31 "F.CrtYd" user "Package Geometry/Place Bound Top")
		(29 "B.CrtYd" user "Package Geometry/Place Bound Bottom")
		(35 "F.Fab" user "Ref Des/Assembly Top")
		(33 "B.Fab" user "Ref Des/Assembly Bottom")
	)
	(footprint ""
		(layer "F.Cu")
		(at 47.2694 -74.803 180)
		(property "Reference" "C312"
			(at 0 0 180)
			(layer "F.SilkS")
			(hide yes)
			(effects
				(font
					(size 1.27 1.27)
				)
			)
		)
		(property "Value" ""
			(at 0 0 180)
			(layer "F.Fab")
			(effects
				(font
					(size 1.27 1.27)
				)
			)
		)
		(duplicate_pad_numbers_are_jumpers no)
		(fp_line
			(start 0.7874 0.4064)
			(end -0.7874 0.4064)
			(stroke
				(width 0.1524)
				(type default)
			)
			(layer "F.SilkS")
		)
		(fp_line
			(start 0.7874 -0.4064)
			(end 0.7874 0.4064)
			(stroke
				(width 0.1524)
				(type default)
			)
			(layer "F.SilkS")
		)
		(fp_line
			(start -0.7874 0.4064)
			(end -0.7874 -0.4064)
			(stroke
				(width 0.1524)
				(type default)
			)
			(layer "F.SilkS")
		)
		(fp_line
			(start -0.7874 -0.4064)
			(end 0.7874 -0.4064)
			(stroke
				(width 0.1524)
				(type default)
			)
			(layer "F.SilkS")
		)
		(fp_line
			(start 0.67945 0.3048)
			(end 0.120396 0.3048)
			(stroke
				(width 0.1)
				(type default)
			)
			(layer "F.Fab")
		)
		(fp_line
			(start 0.67945 -0.3048)
			(end 0.67945 0.3048)
			(stroke
				(width 0.1)
				(type default)
			)
			(layer "F.Fab")
		)
		(fp_line
			(start 0.12065 -0.2794)
			(end 0.12065 -0.3048)
			(stroke
				(width 0.1)
				(type default)
			)
			(layer "F.Fab")
		)
		(fp_line
			(start 0.12065 -0.3048)
			(end 0.67945 -0.3048)
			(stroke
				(width 0.1)
				(type default)
			)
			(layer "F.Fab")
		)
		(fp_line
			(start 0.120396 0.3048)
			(end 0.120396 0.2794)
			(stroke
				(width 0.1)
				(type default)
			)
			(layer "F.Fab")
		)
		(fp_line
			(start 0.120396 0.2794)
			(end -0.12065 0.2794)
			(stroke
				(width 0.1)
				(type default)
			)
			(layer "F.Fab")
		)
		(fp_line
			(start -0.12065 0.3048)
			(end -0.67945 0.3048)
			(stroke
				(width 0.1)
				(type default)
			)
			(layer "F.Fab")
		)
		(fp_line
			(start -0.12065 0.2794)
			(end -0.12065 0.3048)
			(stroke
				(width 0.1)
				(type default)
			)
			(layer "F.Fab")
		)
		(fp_line
			(start -0.12065 -0.2794)
			(end 0.12065 -0.2794)
			(stroke
				(width 0.1)
				(type default)
			)
			(layer "F.Fab")
		)
		(fp_line
			(start -0.12065 -0.305054)
			(end -0.12065 -0.2794)
			(stroke
				(width 0.1)
				(type default)
			)
			(layer "F.Fab")
		)
		(fp_line
			(start -0.67945 0.3048)
			(end -0.67945 -0.305054)
			(stroke
				(width 0.1)
				(type default)
			)
			(layer "F.Fab")
		)
		(fp_line
			(start -0.67945 -0.305054)
			(end -0.12065 -0.305054)
			(stroke
				(width 0.1)
				(type default)
			)
			(layer "F.Fab")
		)
		(pad "1" smd circle
			(at -0.40005 0 180)
			(size 0 0)
			(layers "F.Cu" "F.Mask" "F.Paste")
			(net "P3V3_AUX")
		)
		(pad "2" smd circle
			(at 0.40005 0 180)
			(size 0 0)
			(layers "F.Cu" "F.Mask" "F.Paste")
			(net "GND")
		)
	)
	(footprint ""
		(layer "F.Cu")
		(at 45.085 -82.6008)
		(property "Reference" "R556"
			(at 0 0 0)
			(layer "F.SilkS")
			(hide yes)
			(effects
				(font
					(size 1.27 1.27)
				)
			)
		)
		(property "Value" ""
			(at 0 0 0)
			(layer "F.Fab")
			(effects
				(font
					(size 1.27 1.27)
				)
			)
		)
		(duplicate_pad_numbers_are_jumpers no)
		(fp_line
			(start -0.7874 -0.4064)
			(end 0.7874 -0.4064)
			(stroke
				(width 0.1524)
				(type default)
			)
			(layer "F.SilkS")
		)
		(fp_line
			(start -0.7874 0.4064)
			(end -0.7874 -0.4064)
			(stroke
				(width 0.1524)
				(type default)
			)
			(layer "F.SilkS")
		)
		(fp_line
			(start 0.7874 -0.4064)
			(end 0.7874 0.4064)
			(stroke
				(width 0.1524)
				(type default)
			)
			(layer "F.SilkS")
		)
		(fp_line
			(start 0.7874 0.4064)
			(end -0.7874 0.4064)
			(stroke
				(width 0.1524)
				(type default)
			)
			(layer "F.SilkS")
		)
		(fp_line
			(start -0.67945 -0.305054)
			(end -0.12065 -0.305054)
			(stroke
				(width 0.1)
				(type default)
			)
			(layer "F.Fab")
		)
		(fp_line
			(start -0.67945 0.3048)
			(end -0.67945 -0.305054)
			(stroke
				(width 0.1)
				(type default)
			)
			(layer "F.Fab")
		)
		(fp_line
			(start -0.12065 -0.305054)
			(end -0.12065 -0.2794)
			(stroke
				(width 0.1)
				(type default)
			)
			(layer "F.Fab")
		)
		(fp_line
			(start -0.12065 -0.2794)
			(end 0.12065 -0.2794)
			(stroke
				(width 0.1)
				(type default)
			)
			(layer "F.Fab")
		)
		(fp_line
			(start -0.12065 0.2794)
			(end -0.12065 0.3048)
			(stroke
				(width 0.1)
				(type default)
			)
			(layer "F.Fab")
		)
		(fp_line
			(start -0.12065 0.3048)
			(end -0.67945 0.3048)
			(stroke
				(width 0.1)
				(type default)
			)
			(layer "F.Fab")
		)
		(fp_line
			(start 0.120396 0.2794)
			(end -0.12065 0.2794)
			(stroke
				(width 0.1)
				(type default)
			)
			(layer "F.Fab")
		)
		(fp_line
			(start 0.120396 0.3048)
			(end 0.120396 0.2794)
			(stroke
				(width 0.1)
				(type default)
			)
			(layer "F.Fab")
		)
		(fp_line
			(start 0.12065 -0.3048)
			(end 0.67945 -0.3048)
			(stroke
				(width 0.1)
				(type default)
			)
			(layer "F.Fab")
		)
		(fp_line
			(start 0.12065 -0.2794)
			(end 0.12065 -0.3048)
			(stroke
				(width 0.1)
				(type default)
			)
			(layer "F.Fab")
		)
		(fp_line
			(start 0.67945 -0.3048)
			(end 0.67945 0.3048)
			(stroke
				(width 0.1)
				(type default)
			)
			(layer "F.Fab")
		)
		(fp_line
			(start 0.67945 0.3048)
			(end 0.120396 0.3048)
			(stroke
				(width 0.1)
				(type default)
			)
			(layer "F.Fab")
		)
		(pad "1" smd circle
			(at -0.40005 0)
			(size 0 0)
			(layers "F.Cu" "F.Mask" "F.Paste")
			(net "SPI_BMC_BT_WP1_N_R")
		)
		(pad "2" smd circle
			(at 0.40005 0)
			(size 0 0)
			(layers "F.Cu" "F.Mask" "F.Paste")
			(net "FLASH_LATCH_Q_N_R2")
		)
	)
)
